# T6G (Grand Teton) — schematic netlist excerpt (pin names and nets, part order shuffled) for the footprints in the layout excerpt that follows; sources: Cadence DE-HDL packaged netlist, KiCad conversion of 04192023_DAF0TMB3IC0_F0TG_MB_C_brd_V02_OCP.brd

J100  SCONN288_DDR506112002KQ  IO  pkg DDR288S_1-1VXC  page 106
  VIN_BULK0  = P12V_MEM_CPU1
  RFU0  = NC
  VIN_MGMT  = P3V3_AUX
  HSCL  = I3C_SPD_DDRI_CPU1_SCL
  HSDA  = I3C_SPD_DDRI_CPU1_SDA
  VSS0  = GND
  DQ0_A  = M_I_CPU1_SA_DQ<0>
  VSS1  = GND
  DQ1_A  = M_I_CPU1_SA_DQ<1>
  VSS2  = GND
  DQS0_A_T  = M_I_CPU1_SA_DQS_DP<0>
  DQS0_A_C  = M_I_CPU1_SA_DQS_DN<0>
  VSS3  = GND
  DQ4_A  = M_I_CPU1_SA_DQ<4>
  VSS4  = GND
  DQ5_A  = M_I_CPU1_SA_DQ<5>
  VSS5  = GND
  DQ8_A  = M_I_CPU1_SA_DQ<8>
  VSS6  = GND
  DQ9_A  = M_I_CPU1_SA_DQ<9>
  VSS7  = GND
  DQS1_A_T  = M_I_CPU1_SA_DQS_DP<1>
  DQS1_A_C  = M_I_CPU1_SA_DQS_DN<1>
  VSS8  = GND
  DQ12_A  = M_I_CPU1_SA_DQ<12>
  VSS9  = GND
  DQ13_A  = M_I_CPU1_SA_DQ<13>
  VSS10  = GND
  DQ16_A  = M_I_CPU1_SA_DQ<16>
  VSS11  = GND
  DQ17_A  = M_I_CPU1_SA_DQ<17>
  VSS12  = GND
  DQS2_A_T  = M_I_CPU1_SA_DQS_DP<2>
  DQS2_A_C  = M_I_CPU1_SA_DQS_DN<2>
  VSS13  = GND
  DQ20_A  = M_I_CPU1_SA_DQ<20>
  VSS14  = GND
  DQ21_A  = M_I_CPU1_SA_DQ<21>
  VSS15  = GND
  DQ24_A  = M_I_CPU1_SA_DQ<24>
  VSS16  = GND
  DQ25_A  = M_I_CPU1_SA_DQ<25>
  VSS17  = GND
  DQS3_A_T  = M_I_CPU1_SA_DQS_DP<3>
  DQS3_A_C  = M_I_CPU1_SA_DQS_DN<3>
  VSS18  = GND
  DQ28_A  = M_I_CPU1_SA_DQ<28>
  VSS19  = GND
  DQ29_A  = M_I_CPU1_SA_DQ<29>
  VSS20  = GND
  CB0_A  = M_I_CPU1_SA_CB<0>
  VSS21  = GND
  CB1_A  = M_I_CPU1_SA_CB<1>
  VSS22  = GND
  DQS4_A_T  = M_I_CPU1_SA_DQS_DP<4>
  DQS4_A_C  = M_I_CPU1_SA_DQS_DN<4>
  VSS23  = GND
  CB4_A  = M_I_CPU1_SA_CB<4>
  VSS24  = GND
  CB5_A  = M_I_CPU1_SA_CB<5>
  VSS25  = GND
  ALERT_N  = M_I_CPU1_ALERT_N
  VSS26  = GND
  CS0_A_N  = M_I_CPU1_SA_CS_N<0>
  VSS27  = GND
  CA0_A  = M_I_CPU1_SA_CA<0>
  VSS28  = GND
  CA2_A  = M_I_CPU1_SA_CA<2>
  VSS29  = GND
  CA4_A  = M_I_CPU1_SA_CA<4>
  VSS30  = GND
  CA6_A  = M_I_CPU1_SA_CA<6>
  VSS31  = GND
  PAR_A  = M_I_CPU1_SA_PAR
  VSS32  = GND
  CA0_B  = M_I_CPU1_SB_CA<0>
  VSS33  = GND
  CA2_B  = M_I_CPU1_SB_CA<2>
  VSS34  = GND
  CA4_B  = M_I_CPU1_SB_CA<4>
  VSS35  = GND
  CA6_B  = M_I_CPU1_SB_CA<6>
  VSS36  = GND
  CS0_B_N  = M_I_CPU1_SB_CS_N<0>
  VSS37  = GND
  \lbd||rsp_a_n\  = M_I_CPU1_SA_RSP<0>
  \lbs||rsp_b_n\  = M_I_CPU1_SB_RSP<0>
  VSS38  = GND
  CB4_B  = M_I_CPU1_SB_CB<4>
  VSS39  = GND
  CB5_B  = M_I_CPU1_SB_CB<5>
  VSS40  = GND
  \dqs9_b_t||tdqs9_b_t||dbi4_b_n\  = M_I_CPU1_SB_DQS_DP<9>
  \dqs9_b_c||tdqs9_b_c\  = M_I_CPU1_SB_DQS_DN<9>
  VSS41  = GND
  CB0_B  = M_I_CPU1_SB_CB<0>
  VSS42  = GND
  CB1_B  = M_I_CPU1_SB_CB<1>
  VSS43  = GND
  DQ0_B  = M_I_CPU1_SB_DQ<0>
  VSS44  = GND
  DQ1_B  = M_I_CPU1_SB_DQ<1>
  VSS45  = GND
  DQS0_B_T  = M_I_CPU1_SB_DQS_DP<0>
  DQS0_B_C  = M_I_CPU1_SB_DQS_DN<0>
  VSS46  = GND
  DQ4_B  = M_I_CPU1_SB_DQ<4>
  VSS47  = GND
  DQ5_B  = M_I_CPU1_SB_DQ<5>
  VSS48  = GND
  DQ8_B  = M_I_CPU1_SB_DQ<8>
  VSS49  = GND
  DQ9_B  = M_I_CPU1_SB_DQ<9>
  VSS50  = GND
  DQS1_B_T  = M_I_CPU1_SB_DQS_DP<1>
  DQS1_B_C  = M_I_CPU1_SB_DQS_DN<1>
  VSS51  = GND
  DQ12_B  = M_I_CPU1_SB_DQ<12>
  VSS52  = GND
  DQ13_B  = M_I_CPU1_SB_DQ<13>
  VSS53  = GND
  DQ16_B  = M_I_CPU1_SB_DQ<16>
  VSS54  = GND
  DQ17_B  = M_I_CPU1_SB_DQ<17>
  VSS55  = GND
  DQS2_B_T  = M_I_CPU1_SB_DQS_DP<2>
  DQS2_B_C  = M_I_CPU1_SB_DQS_DN<2>
  VSS56  = GND
  DQ20_B  = M_I_CPU1_SB_DQ<20>
  VSS57  = GND
  DQ21_B  = M_I_CPU1_SB_DQ<21>
  VSS58  = GND
  DQ24_B  = M_I_CPU1_SB_DQ<24>
  VSS59  = GND
  DQ25_B  = M_I_CPU1_SB_DQ<25>
  VSS60  = GND
  DQS3_B_T  = M_I_CPU1_SB_DQS_DP<3>
  DQS3_B_C  = M_I_CPU1_SB_DQS_DN<3>
  VSS61  = GND
  DQ28_B  = M_I_CPU1_SB_DQ<28>
  VSS62  = GND
  DQ29_B  = M_I_CPU1_SB_DQ<29>
  VSS63  = GND
  RFU1  = NC
  VIN_BULK1  = P12V_MEM_CPU1
  VIN_BULK2  = P12V_MEM_CPU1
  \pwr_good||fail_n\  = PWRGD_CHI_CPU1_DIMM
  HAS  = PD_CHI_CPU1_DIMM_SAA
  RFU2  = NC
  RFU3  = NC
  VSS64  = GND
  DQ2_A  = M_I_CPU1_SA_DQ<2>
  VSS65  = GND
  DQ3_A  = M_I_CPU1_SA_DQ<3>
  VSS66  = GND
  \dqs5_a_c||tdqs5_a_c||dqs5_a_t||tdqs5_a_t\  = M_I_CPU1_SA_DQS_DN<5>
  \dqs5_a_t||tdqs5_a_t\  = M_I_CPU1_SA_DQS_DP<5>
  VSS67  = GND
  DQ6_A  = M_I_CPU1_SA_DQ<6>
  VSS68  = GND
  DQ7_A  = M_I_CPU1_SA_DQ<7>
  VSS69  = GND
  DQ10_A  = M_I_CPU1_SA_DQ<10>
  VSS70  = GND
  DQ11_A  = M_I_CPU1_SA_DQ<11>
  VSS71  = GND
  \dqs6_a_c||tdqs6_a_c||dqs6_a_t||tdqs6_a_t\  = M_I_CPU1_SA_DQS_DN<6>
  \dqs6_a_t||tdqs6_a_t\  = M_I_CPU1_SA_DQS_DP<6>
  VSS72  = GND
  DQ14_A  = M_I_CPU1_SA_DQ<14>
  VSS73  = GND
  DQ15_A  = M_I_CPU1_SA_DQ<15>
  VSS74  = GND
  DQ18_A  = M_I_CPU1_SA_DQ<18>
  VSS75  = GND
  DQ19_A  = M_I_CPU1_SA_DQ<19>
  VSS76  = GND
  \dqs7_a_c||tdqs7_a_c\  = M_I_CPU1_SA_DQS_DN<7>
  \dqs7_a_t||tdqs7_a_t\  = M_I_CPU1_SA_DQS_DP<7>
  VSS77  = GND
  DQ22_A  = M_I_CPU1_SA_DQ<22>
  VSS78  = GND
  DQ23_A  = M_I_CPU1_SA_DQ<23>
  VSS79  = GND
  DQ26_A  = M_I_CPU1_SA_DQ<26>
  VSS80  = GND
  DQ27_A  = M_I_CPU1_SA_DQ<27>
  VSS81  = GND
  \dqs8_a_c||tdqs8_a_c\  = M_I_CPU1_SA_DQS_DN<8>
  \dqs8_a_t||tdqs8_a_t\  = M_I_CPU1_SA_DQS_DP<8>
  VSS82  = GND
  DQ30_A  = M_I_CPU1_SA_DQ<30>
  VSS83  = GND
  DQ31_A  = M_I_CPU1_SA_DQ<31>
  VSS84  = GND
  CB2_A  = M_I_CPU1_SA_CB<2>
  VSS85  = GND
  CB3_A  = M_I_CPU1_SA_CB<3>
  VSS86  = GND
  \dqs9_a_c||tdqs9_a_c\  = M_I_CPU1_SA_DQS_DN<9>
  \dqs9_a_t||tdqs9_a_t\  = M_I_CPU1_SA_DQS_DP<9>
  VSS87  = GND
  CB6_A  = M_I_CPU1_SA_CB<6>
  VSS88  = GND
  CB7_A  = M_I_CPU1_SA_CB<7>
  VSS89  = GND
  RESET_N  = M_I_CPU1_RESET_N
  VSS90  = GND
  CS1_A_N  = M_I_CPU1_SA_CS_N<1>
  VSS91  = GND
  CA1_A  = M_I_CPU1_SA_CA<1>
  VSS92  = GND
  CA3_A  = M_I_CPU1_SA_CA<3>
  VSS93  = GND
  CA5_A  = M_I_CPU1_SA_CA<5>
  VSS94  = GND
  CK_T  = M_I_CPU1_CLK_DP<0>
  CK_C  = M_I_CPU1_CLK_DN<0>
  VSS95  = GND
  RFU4  = NC
  CA1_B  = M_I_CPU1_SB_CA<1>
  VSS96  = GND
  CA3_B  = M_I_CPU1_SB_CA<3>
  VSS97  = GND
  CA5_B  = M_I_CPU1_SB_CA<5>
  VSS98  = GND
  PAR_B  = M_I_CPU1_SB_PAR
  VSS99  = GND
  CS1_B_N  = M_I_CPU1_SB_CS_N<1>
  VSS100  = GND
  RFU5  = NC
  RFU6  = NC
  VSS101  = GND
  CB6_B  = M_I_CPU1_SB_CB<6>
  VSS102  = GND
  CB7_B  = M_I_CPU1_SB_CB<7>
  VSS103  = GND
  DQS4_B_C  = M_I_CPU1_SB_DQS_DN<4>
  DQS4_B_T  = M_I_CPU1_SB_DQS_DP<4>
  VSS104  = GND
  CB2_B  = M_I_CPU1_SB_CB<2>
  VSS105  = GND
  CB3_B  = M_I_CPU1_SB_CB<3>
  VSS106  = GND
  DQ2_B  = M_I_CPU1_SB_DQ<2>
  VSS107  = GND
  DQ3_B  = M_I_CPU1_SB_DQ<3>
  VSS108  = GND
  \dqs5_b_c||tdqs5_b_c\  = M_I_CPU1_SB_DQS_DN<5>
  \dqs5_b_t||tdqs5_b_t\  = M_I_CPU1_SB_DQS_DP<5>
  VSS109  = GND
  DQ6_B  = M_I_CPU1_SB_DQ<6>
  VSS110  = GND
  DQ7_B  = M_I_CPU1_SB_DQ<7>
  VSS111  = GND
  DQ10_B  = M_I_CPU1_SB_DQ<10>
  VSS112  = GND
  DQ11_B  = M_I_CPU1_SB_DQ<11>
  VSS113  = GND
  \dqs6_b_c||tdqs6_b_c\  = M_I_CPU1_SB_DQS_DN<6>
  \dqs6_b_t||tdqs6_b_t\  = M_I_CPU1_SB_DQS_DP<6>
  VSS114  = GND
  DQ14_B  = M_I_CPU1_SB_DQ<14>
  VSS115  = GND
  DQ15_B  = M_I_CPU1_SB_DQ<15>
  VSS116  = GND
  DQ18_B  = M_I_CPU1_SB_DQ<18>
  VSS117  = GND
  DQ19_B  = M_I_CPU1_SB_DQ<19>
  VSS118  = GND
  \dqs7_b_c||tdqs7_b_c\  = M_I_CPU1_SB_DQS_DN<7>
  \dqs7_b_t||tdqs7_b_t\  = M_I_CPU1_SB_DQS_DP<7>
  VSS119  = GND
  DQ22_B  = M_I_CPU1_SB_DQ<22>
  VSS120  = GND
  DQ23_B  = M_I_CPU1_SB_DQ<23>
  VSS121  = GND
  DQ26_B  = M_I_CPU1_SB_DQ<26>
  VSS122  = GND
  DQ27_B  = M_I_CPU1_SB_DQ<27>
  VSS123  = GND
  \dqs8_b_c||tdqs8_b_c\  = M_I_CPU1_SB_DQS_DN<8>
  \dqs8_b_t||tdqs8_b_t\  = M_I_CPU1_SB_DQS_DP<8>
  VSS124  = GND
  DQ30_B  = M_I_CPU1_SB_DQ<30>
  VSS125  = GND
  DQ31_B  = M_I_CPU1_SB_DQ<31>
  VSS126  = GND
  G1  = GND
  G2  = GND
  G3  = GND

(kicad_pcb
	(version 20260206)
	(generator "pcbnew")
	(generator_version "10.0")
	(general
		(thickness 1.6)
		(legacy_teardrops no)
	)
	(paper "A4")
	(title_block
		(title "04192023_DAF0TMB3IC0_F0TG_MB_C_brd_V02_OCP.brd")
		(comment 1 "Grand Teton / footprint 230 of 8354 (J100), pads 139-184 of 291")
	)
	(layers
		(0 "F.Cu" signal "TOP")
		(4 "In1.Cu" signal "GND")
		(6 "In2.Cu" signal "IN1")
		(8 "In3.Cu" signal "GND1")
		(10 "In4.Cu" signal "IN2")
		(12 "In5.Cu" signal "GND2")
		(14 "In6.Cu" signal "IN3")
		(16 "In7.Cu" signal "GND3")
		(18 "In8.Cu" signal "VCC")
		(20 "In9.Cu" signal "VCC1")
		(22 "In10.Cu" signal "GND4")
		(24 "In11.Cu" signal "IN4")
		(26 "In12.Cu" signal "GND5")
		(28 "In13.Cu" signal "IN5")
		(30 "In14.Cu" signal "GND6")
		(32 "In15.Cu" signal "IN6")
		(34 "In16.Cu" signal "GND7")
		(2 "B.Cu" signal "BOTTOM")
		(9 "F.Adhes" user "F.Adhesive")
		(11 "B.Adhes" user "B.Adhesive")
		(13 "F.Paste" user "Package Geometry/Pastemask Top")
		(15 "B.Paste" user "Package Geometry/Pastemask Bottom")
		(5 "F.SilkS" user "Ref Des/Silkscreen Top")
		(7 "B.SilkS" user "Ref Des/Silkscreen Bottom")
		(1 "F.Mask" user "Board Geometry/Soldermask Top")
		(3 "B.Mask" user "Board Geometry/Soldermask Bottom")
		(17 "Dwgs.User" user "User.Drawings")
		(19 "Cmts.User" user "User.Comments")
		(21 "Eco1.User" user "User.Eco1")
		(23 "Eco2.User" user "User.Eco2")
		(25 "Edge.Cuts" user "Board Geometry/Outline")
		(27 "Margin" user)
		(31 "F.CrtYd" user "Package Geometry/Place Bound Top")
		(29 "B.CrtYd" user "Package Geometry/Place Bound Bottom")
		(35 "F.Fab" user "Ref Des/Assembly Top")
		(33 "B.Fab" user "Ref Des/Assembly Bottom")
	)
	(footprint ""
		(layer "F.Cu")
		(at 181.566058 -255.560322 180)
		(property "Reference" "J100"
			(at -2.7178 -81.857088 0)
			(unlocked yes)
			(layer "F.SilkS")
			(effects
				(font
					(size 0.7874 0.5842)
					(thickness 0.1524)
				)
			)
		)
		(property "Value" ""
			(at 0 0 180)
			(layer "F.Fab")
			(effects
				(font
					(size 1.27 1.27)
				)
			)
		)
		(duplicate_pad_numbers_are_jumpers no)
		(pad "139" smd rect
			(at -2.050034 59.075066 90)
			(size 0.519938 1.4986)
			(layers "F.Cu" "F.Mask" "F.Paste")
			(net "GND")
		)
		(pad "140" smd rect
			(at -2.050034 59.92495 90)
			(size 0.519938 1.4986)
			(layers "F.Cu" "F.Mask" "F.Paste")
			(net "M_I_CPU1_SB_DQ<28>")
		)
		(pad "141" smd rect
			(at -2.050034 60.775088 90)
			(size 0.519938 1.4986)
			(layers "F.Cu" "F.Mask" "F.Paste")
			(net "GND")
		)
		(pad "142" smd rect
			(at -2.050034 61.624972 90)
			(size 0.519938 1.4986)
			(layers "F.Cu" "F.Mask" "F.Paste")
			(net "M_I_CPU1_SB_DQ<29>")
		)
		(pad "143" smd rect
			(at -2.050034 62.47511 90)
			(size 0.519938 1.4986)
			(layers "F.Cu" "F.Mask" "F.Paste")
			(net "GND")
		)
		(pad "144" smd rect
			(at -2.050034 63.324994 90)
			(size 0.519938 1.4986)
			(layers "F.Cu" "F.Mask" "F.Paste")
			(net "Net_2369")
		)
		(pad "145" smd rect
			(at 2.050034 -63.324994 90)
			(size 0.519938 1.4986)
			(layers "F.Cu" "F.Mask" "F.Paste")
			(net "P12V_MEM_CPU1")
		)
		(pad "146" smd rect
			(at 2.050034 -62.47511 90)
			(size 0.519938 1.4986)
			(layers "F.Cu" "F.Mask" "F.Paste")
			(net "P12V_MEM_CPU1")
		)
		(pad "147" smd rect
			(at 2.050034 -61.624972 90)
			(size 0.519938 1.4986)
			(layers "F.Cu" "F.Mask" "F.Paste")
			(net "PWRGD_CHI_CPU1_DIMM")
		)
		(pad "148" smd rect
			(at 2.050034 -60.775088 90)
			(size 0.519938 1.4986)
			(layers "F.Cu" "F.Mask" "F.Paste")
			(net "PD_CHI_CPU1_DIMM_SAA")
		)
		(pad "149" smd rect
			(at 2.050034 -59.92495 90)
			(size 0.519938 1.4986)
			(layers "F.Cu" "F.Mask" "F.Paste")
			(net "Net_2370")
		)
		(pad "150" smd rect
			(at 2.050034 -59.075066 90)
			(size 0.519938 1.4986)
			(layers "F.Cu" "F.Mask" "F.Paste")
			(net "Net_2371")
		)
		(pad "151" smd rect
			(at 2.050034 -58.224928 90)
			(size 0.519938 1.4986)
			(layers "F.Cu" "F.Mask" "F.Paste")
			(net "GND")
		)
		(pad "152" smd rect
			(at 2.050034 -57.375044 90)
			(size 0.519938 1.4986)
			(layers "F.Cu" "F.Mask" "F.Paste")
			(net "M_I_CPU1_SA_DQ<2>")
		)
		(pad "153" smd rect
			(at 2.050034 -56.524906 90)
			(size 0.519938 1.4986)
			(layers "F.Cu" "F.Mask" "F.Paste")
			(net "GND")
		)
		(pad "154" smd rect
			(at 2.050034 -55.675022 90)
			(size 0.519938 1.4986)
			(layers "F.Cu" "F.Mask" "F.Paste")
			(net "M_I_CPU1_SA_DQ<3>")
		)
		(pad "155" smd rect
			(at 2.050034 -54.824884 90)
			(size 0.519938 1.4986)
			(layers "F.Cu" "F.Mask" "F.Paste")
			(net "GND")
		)
		(pad "156" smd rect
			(at 2.050034 -53.975 90)
			(size 0.519938 1.4986)
			(layers "F.Cu" "F.Mask" "F.Paste")
			(net "M_I_CPU1_SA_DQS_DN<5>")
		)
		(pad "157" smd rect
			(at 2.050034 -53.125116 90)
			(size 0.519938 1.4986)
			(layers "F.Cu" "F.Mask" "F.Paste")
			(net "M_I_CPU1_SA_DQS_DP<5>")
		)
		(pad "158" smd rect
			(at 2.050034 -52.274978 90)
			(size 0.519938 1.4986)
			(layers "F.Cu" "F.Mask" "F.Paste")
			(net "GND")
		)
		(pad "159" smd rect
			(at 2.050034 -51.425094 90)
			(size 0.519938 1.4986)
			(layers "F.Cu" "F.Mask" "F.Paste")
			(net "M_I_CPU1_SA_DQ<6>")
		)
		(pad "160" smd rect
			(at 2.050034 -50.574956 90)
			(size 0.519938 1.4986)
			(layers "F.Cu" "F.Mask" "F.Paste")
			(net "GND")
		)
		(pad "161" smd rect
			(at 2.050034 -49.725072 90)
			(size 0.519938 1.4986)
			(layers "F.Cu" "F.Mask" "F.Paste")
			(net "M_I_CPU1_SA_DQ<7>")
		)
		(pad "162" smd rect
			(at 2.050034 -48.874934 90)
			(size 0.519938 1.4986)
			(layers "F.Cu" "F.Mask" "F.Paste")
			(net "GND")
		)
		(pad "163" smd rect
			(at 2.050034 -48.02505 90)
			(size 0.519938 1.4986)
			(layers "F.Cu" "F.Mask" "F.Paste")
			(net "M_I_CPU1_SA_DQ<10>")
		)
		(pad "164" smd rect
			(at 2.050034 -47.174912 90)
			(size 0.519938 1.4986)
			(layers "F.Cu" "F.Mask" "F.Paste")
			(net "GND")
		)
		(pad "165" smd rect
			(at 2.050034 -46.325028 90)
			(size 0.519938 1.4986)
			(layers "F.Cu" "F.Mask" "F.Paste")
			(net "M_I_CPU1_SA_DQ<11>")
		)
		(pad "166" smd rect
			(at 2.050034 -45.47489 90)
			(size 0.519938 1.4986)
			(layers "F.Cu" "F.Mask" "F.Paste")
			(net "GND")
		)
		(pad "167" smd rect
			(at 2.050034 -44.625006 90)
			(size 0.519938 1.4986)
			(layers "F.Cu" "F.Mask" "F.Paste")
			(net "M_I_CPU1_SA_DQS_DN<6>")
		)
		(pad "168" smd rect
			(at 2.050034 -43.775122 90)
			(size 0.519938 1.4986)
			(layers "F.Cu" "F.Mask" "F.Paste")
			(net "M_I_CPU1_SA_DQS_DP<6>")
		)
		(pad "169" smd rect
			(at 2.050034 -42.924984 90)
			(size 0.519938 1.4986)
			(layers "F.Cu" "F.Mask" "F.Paste")
			(net "GND")
		)
		(pad "170" smd rect
			(at 2.050034 -42.0751 90)
			(size 0.519938 1.4986)
			(layers "F.Cu" "F.Mask" "F.Paste")
			(net "M_I_CPU1_SA_DQ<14>")
		)
		(pad "171" smd rect
			(at 2.050034 -41.224962 90)
			(size 0.519938 1.4986)
			(layers "F.Cu" "F.Mask" "F.Paste")
			(net "GND")
		)
		(pad "172" smd rect
			(at 2.050034 -40.375078 90)
			(size 0.519938 1.4986)
			(layers "F.Cu" "F.Mask" "F.Paste")
			(net "M_I_CPU1_SA_DQ<15>")
		)
		(pad "173" smd rect
			(at 2.050034 -39.52494 90)
			(size 0.519938 1.4986)
			(layers "F.Cu" "F.Mask" "F.Paste")
			(net "GND")
		)
		(pad "174" smd rect
			(at 2.050034 -38.675056 90)
			(size 0.519938 1.4986)
			(layers "F.Cu" "F.Mask" "F.Paste")
			(net "M_I_CPU1_SA_DQ<18>")
		)
		(pad "175" smd rect
			(at 2.050034 -37.824918 90)
			(size 0.519938 1.4986)
			(layers "F.Cu" "F.Mask" "F.Paste")
			(net "GND")
		)
		(pad "176" smd rect
			(at 2.050034 -36.975034 90)
			(size 0.519938 1.4986)
			(layers "F.Cu" "F.Mask" "F.Paste")
			(net "M_I_CPU1_SA_DQ<19>")
		)
		(pad "177" smd rect
			(at 2.050034 -36.124896 90)
			(size 0.519938 1.4986)
			(layers "F.Cu" "F.Mask" "F.Paste")
			(net "GND")
		)
		(pad "178" smd rect
			(at 2.050034 -35.275012 90)
			(size 0.519938 1.4986)
			(layers "F.Cu" "F.Mask" "F.Paste")
			(net "M_I_CPU1_SA_DQS_DN<7>")
		)
		(pad "179" smd rect
			(at 2.050034 -34.425128 90)
			(size 0.519938 1.4986)
			(layers "F.Cu" "F.Mask" "F.Paste")
			(net "M_I_CPU1_SA_DQS_DP<7>")
		)
		(pad "180" smd rect
			(at 2.050034 -33.57499 90)
			(size 0.519938 1.4986)
			(layers "F.Cu" "F.Mask" "F.Paste")
			(net "GND")
		)
		(pad "181" smd rect
			(at 2.050034 -32.725106 90)
			(size 0.519938 1.4986)
			(layers "F.Cu" "F.Mask" "F.Paste")
			(net "M_I_CPU1_SA_DQ<22>")
		)
		(pad "182" smd rect
			(at 2.050034 -31.874968 90)
			(size 0.519938 1.4986)
			(layers "F.Cu" "F.Mask" "F.Paste")
			(net "GND")
		)
		(pad "183" smd rect
			(at 2.050034 -31.025084 90)
			(size 0.519938 1.4986)
			(layers "F.Cu" "F.Mask" "F.Paste")
			(net "M_I_CPU1_SA_DQ<23>")
		)
		(pad "184" smd rect
			(at 2.050034 -30.174946 90)
			(size 0.519938 1.4986)
			(layers "F.Cu" "F.Mask" "F.Paste")
			(net "GND")
		)
	)
)
